# T6G (Grand Teton) — schematic netlist excerpt (pin names and nets, part order shuffled) for the footprints in the layout excerpt that follows; sources: Cadence DE-HDL packaged netlist, KiCad conversion of 04192023_DAF0TMB3IC0_F0TG_MB_C_brd_V02_OCP.brd

R989  Q_RES  0 5% EMPTY  pkg 0402LF  page 159 : A = I3C_0_SPD_DDRAF_CPU1_R_SDA ; B = I3C_SPD_DDRAF_CPU1_BYPASS_SDA
R46  Q_RES  0 5% CHIP  pkg 0402LF  page 131 : A = USB2_P11_DP ; B = USB2_CPU0_P11_DP

(kicad_pcb
	(version 20260206)
	(generator "pcbnew")
	(generator_version "10.0")
	(general
		(thickness 1.6)
		(legacy_teardrops no)
	)
	(paper "A4")
	(title_block
		(title "04192023_DAF0TMB3IC0_F0TG_MB_C_brd_V02_OCP.brd")
		(comment 1 "Grand Teton / footprints 1018-1019 of 8354")
	)
	(layers
		(0 "F.Cu" signal "TOP")
		(4 "In1.Cu" signal "GND")
		(6 "In2.Cu" signal "IN1")
		(8 "In3.Cu" signal "GND1")
		(10 "In4.Cu" signal "IN2")
		(12 "In5.Cu" signal "GND2")
		(14 "In6.Cu" signal "IN3")
		(16 "In7.Cu" signal "GND3")
		(18 "In8.Cu" signal "VCC")
		(20 "In9.Cu" signal "VCC1")
		(22 "In10.Cu" signal "GND4")
		(24 "In11.Cu" signal "IN4")
		(26 "In12.Cu" signal "GND5")
		(28 "In13.Cu" signal "IN5")
		(30 "In14.Cu" signal "GND6")
		(32 "In15.Cu" signal "IN6")
		(34 "In16.Cu" signal "GND7")
		(2 "B.Cu" signal "BOTTOM")
		(9 "F.Adhes" user "F.Adhesive")
		(11 "B.Adhes" user "B.Adhesive")
		(13 "F.Paste" user "Package Geometry/Pastemask Top")
		(15 "B.Paste" user "Package Geometry/Pastemask Bottom")
		(5 "F.SilkS" user "Ref Des/Silkscreen Top")
		(7 "B.SilkS" user "Ref Des/Silkscreen Bottom")
		(1 "F.Mask" user "Board Geometry/Soldermask Top")
		(3 "B.Mask" user "Board Geometry/Soldermask Bottom")
		(17 "Dwgs.User" user "User.Drawings")
		(19 "Cmts.User" user "User.Comments")
		(21 "Eco1.User" user "User.Eco1")
		(23 "Eco2.User" user "User.Eco2")
		(25 "Edge.Cuts" user "Board Geometry/Outline")
		(27 "Margin" user)
		(31 "F.CrtYd" user "Package Geometry/Place Bound Top")
		(29 "B.CrtYd" user "Package Geometry/Place Bound Bottom")
		(35 "F.Fab" user "Ref Des/Assembly Top")
		(33 "B.Fab" user "Ref Des/Assembly Bottom")
	)
	(footprint ""
		(layer "F.Cu")
		(at 390.513316 -22.789134 90)
		(property "Reference" "R46"
			(at 0 0 90)
			(layer "F.SilkS")
			(hide yes)
			(effects
				(font
					(size 1.27 1.27)
				)
			)
		)
		(property "Value" ""
			(at 0 0 90)
			(layer "F.Fab")
			(effects
				(font
					(size 1.27 1.27)
				)
			)
		)
		(duplicate_pad_numbers_are_jumpers no)
		(fp_line
			(start 0.7874 0.011684)
			(end 0.7874 0.4064)
			(stroke
				(width 0.1524)
				(type default)
			)
			(layer "F.SilkS")
		)
		(fp_line
			(start 0.7874 0.4064)
			(end -0.7874 0.4064)
			(stroke
				(width 0.1524)
				(type default)
			)
			(layer "F.SilkS")
		)
		(fp_line
			(start -0.7874 0.4064)
			(end -0.7874 0.011684)
			(stroke
				(width 0.1524)
				(type default)
			)
			(layer "F.SilkS")
		)
		(fp_line
			(start -0.12065 -0.305054)
			(end -0.12065 -0.2794)
			(stroke
				(width 0.1)
				(type default)
			)
			(layer "F.Fab")
		)
		(fp_line
			(start -0.67945 -0.305054)
			(end -0.12065 -0.305054)
			(stroke
				(width 0.1)
				(type default)
			)
			(layer "F.Fab")
		)
		(fp_line
			(start 0.67945 -0.3048)
			(end 0.67945 0.3048)
			(stroke
				(width 0.1)
				(type default)
			)
			(layer "F.Fab")
		)
		(fp_line
			(start 0.12065 -0.3048)
			(end 0.67945 -0.3048)
			(stroke
				(width 0.1)
				(type default)
			)
			(layer "F.Fab")
		)
		(fp_line
			(start 0.12065 -0.2794)
			(end 0.12065 -0.3048)
			(stroke
				(width 0.1)
				(type default)
			)
			(layer "F.Fab")
		)
		(fp_line
			(start -0.12065 -0.2794)
			(end 0.12065 -0.2794)
			(stroke
				(width 0.1)
				(type default)
			)
			(layer "F.Fab")
		)
		(fp_line
			(start 0.120396 0.2794)
			(end -0.12065 0.2794)
			(stroke
				(width 0.1)
				(type default)
			)
			(layer "F.Fab")
		)
		(fp_line
			(start -0.12065 0.2794)
			(end -0.12065 0.3048)
			(stroke
				(width 0.1)
				(type default)
			)
			(layer "F.Fab")
		)
		(fp_line
			(start 0.67945 0.3048)
			(end 0.120396 0.3048)
			(stroke
				(width 0.1)
				(type default)
			)
			(layer "F.Fab")
		)
		(fp_line
			(start 0.120396 0.3048)
			(end 0.120396 0.2794)
			(stroke
				(width 0.1)
				(type default)
			)
			(layer "F.Fab")
		)
		(fp_line
			(start -0.12065 0.3048)
			(end -0.67945 0.3048)
			(stroke
				(width 0.1)
				(type default)
			)
			(layer "F.Fab")
		)
		(fp_line
			(start -0.67945 0.3048)
			(end -0.67945 -0.305054)
			(stroke
				(width 0.1)
				(type default)
			)
			(layer "F.Fab")
		)
		(pad "1" smd circle
			(at -0.40005 0 90)
			(size 0 0)
			(layers "F.Cu" "F.Mask" "F.Paste")
			(net "USB2_P11_DP")
		)
		(pad "2" smd circle
			(at 0.40005 0 90)
			(size 0 0)
			(layers "F.Cu" "F.Mask" "F.Paste")
			(net "USB2_CPU0_P11_DP")
		)
	)
	(footprint ""
		(layer "F.Cu")
		(at 43.4721 -171.831)
		(property "Reference" "R989"
			(at 0 0 0)
			(layer "F.SilkS")
			(hide yes)
			(effects
				(font
					(size 1.27 1.27)
				)
			)
		)
		(property "Value" ""
			(at 0 0 0)
			(layer "F.Fab")
			(effects
				(font
					(size 1.27 1.27)
				)
			)
		)
		(duplicate_pad_numbers_are_jumpers no)
		(fp_line
			(start -0.7874 -0.4064)
			(end 0.7874 -0.4064)
			(stroke
				(width 0.1524)
				(type default)
			)
			(layer "F.SilkS")
		)
		(fp_line
			(start -0.7874 0.4064)
			(end -0.7874 -0.4064)
			(stroke
				(width 0.1524)
				(type default)
			)
			(layer "F.SilkS")
		)
		(fp_line
			(start 0.7874 -0.4064)
			(end 0.7874 0.4064)
			(stroke
				(width 0.1524)
				(type default)
			)
			(layer "F.SilkS")
		)
		(fp_line
			(start 0.7874 0.4064)
			(end -0.7874 0.4064)
			(stroke
				(width 0.1524)
				(type default)
			)
			(layer "F.SilkS")
		)
		(fp_line
			(start -0.67945 -0.305054)
			(end -0.12065 -0.305054)
			(stroke
				(width 0.1)
				(type default)
			)
			(layer "F.Fab")
		)
		(fp_line
			(start -0.67945 0.3048)
			(end -0.67945 -0.305054)
			(stroke
				(width 0.1)
				(type default)
			)
			(layer "F.Fab")
		)
		(fp_line
			(start -0.12065 -0.305054)
			(end -0.12065 -0.2794)
			(stroke
				(width 0.1)
				(type default)
			)
			(layer "F.Fab")
		)
		(fp_line
			(start -0.12065 -0.2794)
			(end 0.12065 -0.2794)
			(stroke
				(width 0.1)
				(type default)
			)
			(layer "F.Fab")
		)
		(fp_line
			(start -0.12065 0.2794)
			(end -0.12065 0.3048)
			(stroke
				(width 0.1)
				(type default)
			)
			(layer "F.Fab")
		)
		(fp_line
			(start -0.12065 0.3048)
			(end -0.67945 0.3048)
			(stroke
				(width 0.1)
				(type default)
			)
			(layer "F.Fab")
		)
		(fp_line
			(start 0.120396 0.2794)
			(end -0.12065 0.2794)
			(stroke
				(width 0.1)
				(type default)
			)
			(layer "F.Fab")
		)
		(fp_line
			(start 0.120396 0.3048)
			(end 0.120396 0.2794)
			(stroke
				(width 0.1)
				(type default)
			)
			(layer "F.Fab")
		)
		(fp_line
			(start 0.12065 -0.3048)
			(end 0.67945 -0.3048)
			(stroke
				(width 0.1)
				(type default)
			)
			(layer "F.Fab")
		)
		(fp_line
			(start 0.12065 -0.2794)
			(end 0.12065 -0.3048)
			(stroke
				(width 0.1)
				(type default)
			)
			(layer "F.Fab")
		)
		(fp_line
			(start 0.67945 -0.3048)
			(end 0.67945 0.3048)
			(stroke
				(width 0.1)
				(type default)
			)
			(layer "F.Fab")
		)
		(fp_line
			(start 0.67945 0.3048)
			(end 0.120396 0.3048)
			(stroke
				(width 0.1)
				(type default)
			)
			(layer "F.Fab")
		)
		(pad "1" smd rect
			(at -0.40005 0 180)
			(size 0.4572 0.508)
			(layers "F.Cu" "F.Mask" "F.Paste")
			(net "I3C_0_SPD_DDRAF_CPU1_R_SDA")
		)
		(pad "2" smd rect
			(at 0.40005 0 180)
			(size 0.4572 0.508)
			(layers "F.Cu" "F.Mask" "F.Paste")
			(net "I3C_SPD_DDRAF_CPU1_BYPASS_SDA")
		)
	)
)
